FILE_TYPE = MULTI_PHYS_TABLE;
PART 'GTL2014'
{======================================================================================================================================================================}
:PACK_TYPE| MATERIAL |   PART_NUMBER   = EnvComp |  PART_NUMBER |  JEDEC_TYPE      | CLASS |  DESCRIPTION                           | HEIGHT     |COMPONENT_TYPE|LPID | SPEED_URL | Status |RPL| AML | Bus_Unit | Days ;
{======================================================================================================================================================================}
'SM'      | 'IC'     | 'D66151-001'(!) = 'NO;NO;NO;NO;NO;NO' | 'D66151-001' | 'SSOP14_18_65MA' | 'IC'  | 'IC,LOG,TRANSCEIVE,TSSOP,GTL2014,NI3S' | '0.043 IN' | 'SUB50'      | '1094' | 'http://speed.intel.com:8081/speed/module/pdm/item/pdm_item_detail_direct.asp?item_cde=D66151-001&item_rev=01&url_param=unused' | 'Unqual' | 'YES' | '1' | 'SMO_IC' | '84' 
'SM'      | 'EMPTY'  | 'D66151-001'(!) = 'NO;NO;NO;NO;NO;NO' | 'D66151-001' | 'SSOP14_18_65MA' | 'IO'  | 'IC,LOG,TRANSCEIVE,TSSOP,GTL2014,NI3S' | '0.043 IN' | 'SUB50'      | '1094' | 'http://speed.intel.com:8081/speed/module/pdm/item/pdm_item_detail_direct.asp?item_cde=D66151-001&item_rev=01&url_param=unused' | 'Unqual' | 'YES' | '1' | 'SMO_IC' | '84' 
END_PART
END.
